# BASEBOARD_FAB2 (Tioga Pass) — schematic netlist excerpt (pin names and nets, part order shuffled) for the footprints in the layout excerpt that follows; sources: Cadence DE-HDL packaged netlist, KiCad conversion of Wiwynn_Tioga_Pass_MB.brd

C6L10  CAP  10UF 16V 10% X6S  pkg 0805  page 234 : A = VR_FET_SW_P12V_STBY_PVPP_KLM ; B = GND
C7G42  SC1U10V2KX-4-GP  10%  pkg SMD-BCG6  page 216 : \1\ = P5V_STBY ; \2\ = GND
R9R9  RES  0.0 5% CHIP  pkg 0402  page 181 : A = FAN_TACH3 ; B = FAN_TACH3_R

(kicad_pcb
	(version 20260206)
	(generator "pcbnew")
	(generator_version "10.0")
	(general
		(thickness 1.6)
		(legacy_teardrops no)
	)
	(paper "A4")
	(title_block
		(title "Wiwynn_Tioga_Pass_MB.brd")
		(comment 1 "Tioga Pass / footprints 4483-4485 of 4770")
	)
	(layers
		(0 "F.Cu" signal "TOP")
		(4 "In1.Cu" signal "L2GND")
		(6 "In2.Cu" signal "L3")
		(8 "In3.Cu" signal "L4GND")
		(10 "In4.Cu" signal "L5")
		(12 "In5.Cu" signal "L6GND")
		(14 "In6.Cu" signal "L7VCC")
		(16 "In7.Cu" signal "L8VCC")
		(18 "In8.Cu" signal "L9GND")
		(20 "In9.Cu" signal "L10")
		(22 "In10.Cu" signal "L11GND")
		(24 "In11.Cu" signal "L12")
		(26 "In12.Cu" signal "L13GND")
		(2 "B.Cu" signal "BOTTOM")
		(9 "F.Adhes" user "F.Adhesive")
		(11 "B.Adhes" user "B.Adhesive")
		(13 "F.Paste" user "Package Geometry/Pastemask Top")
		(15 "B.Paste" user "Package Geometry/Pastemask Bottom")
		(5 "F.SilkS" user "Ref Des/Silkscreen Top")
		(7 "B.SilkS" user "Ref Des/Silkscreen Bottom")
		(1 "F.Mask" user "Board Geometry/Soldermask Top")
		(3 "B.Mask" user "Board Geometry/Soldermask Bottom")
		(17 "Dwgs.User" user "User.Drawings")
		(19 "Cmts.User" user "User.Comments")
		(21 "Eco1.User" user "User.Eco1")
		(23 "Eco2.User" user "User.Eco2")
		(25 "Edge.Cuts" user "Board Geometry/Outline")
		(27 "Margin" user)
		(31 "F.CrtYd" user "Package Geometry/Place Bound Top")
		(29 "B.CrtYd" user "Package Geometry/Place Bound Bottom")
		(35 "F.Fab" user "Ref Des/Assembly Top")
		(33 "B.Fab" user "Ref Des/Assembly Bottom")
	)
	(footprint ""
		(layer "B.Cu")
		(at 9.7536 -41.6814 -90)
		(property "Reference" "R9R9"
			(at 0 0 90)
			(layer "B.SilkS")
			(hide yes)
			(effects
				(font
					(size 1.27 1.27)
				)
				(justify mirror)
			)
		)
		(property "Value" ""
			(at 0 0 90)
			(layer "B.Fab")
			(effects
				(font
					(size 1.27 1.27)
				)
				(justify mirror)
			)
		)
		(duplicate_pad_numbers_are_jumpers no)
		(fp_poly
			(pts
				(xy 0.2794 -0.1016) (xy -0.2794 -0.1016) (xy -0.2794 0.9906) (xy 0.2794 0.9906)
			)
			(stroke
				(width 0)
				(type default)
			)
			(fill no)
			(layer "B.CrtYd")
		)
		(fp_line
			(start -0.2794 0.9906)
			(end -0.2794 -0.1016)
			(stroke
				(width 0.1)
				(type default)
			)
			(layer "B.Fab")
		)
		(fp_line
			(start 0.2794 0.9906)
			(end -0.2794 0.9906)
			(stroke
				(width 0.1)
				(type default)
			)
			(layer "B.Fab")
		)
		(fp_line
			(start -0.2794 -0.1016)
			(end 0.2794 -0.1016)
			(stroke
				(width 0.1)
				(type default)
			)
			(layer "B.Fab")
		)
		(fp_line
			(start 0.2794 -0.1016)
			(end 0.2794 0.9906)
			(stroke
				(width 0.1)
				(type default)
			)
			(layer "B.Fab")
		)
		(pad "1" smd rect
			(at 0 0 90)
			(size 0.508 0.508)
			(layers "B.Cu" "B.Mask" "B.Paste")
			(net "FAN_TACH3")
		)
		(pad "2" smd rect
			(at 0 0.889 90)
			(size 0.508 0.508)
			(layers "B.Cu" "B.Mask" "B.Paste")
			(net "FAN_TACH3_R")
		)
		(zone
			(layer "B.Cu")
			(hatch none 0.5)
			(connect_pads
				(clearance 0)
			)
			(min_thickness 0.25)
			(keepout
				(tracks not_allowed)
				(vias allowed)
				(pads allowed)
				(copperpour not_allowed)
				(footprints allowed)
			)
			(placement
				(enabled no)
				(sheetname "")
			)
			(fill
				(thermal_gap 0.5)
				(thermal_bridge_width 0.5)
				(island_removal_mode 0)
			)
			(polygon
				(pts
					(xy 9.1186 -41.4274) (xy 9.1186 -41.9354) (xy 9.4996 -41.9354) (xy 9.4996 -41.4274)
				)
			)
		)
		(zone
			(layer "B.Cu")
			(hatch none 0.5)
			(connect_pads
				(clearance 0)
			)
			(min_thickness 0.25)
			(keepout
				(tracks allowed)
				(vias not_allowed)
				(pads allowed)
				(copperpour not_allowed)
				(footprints allowed)
			)
			(placement
				(enabled no)
				(sheetname "")
			)
			(fill
				(thermal_gap 0.5)
				(thermal_bridge_width 0.5)
				(island_removal_mode 0)
			)
			(polygon
				(pts
					(xy 9.4996 -41.4274) (xy 9.4996 -41.9354) (xy 9.1186 -41.9354) (xy 9.1186 -41.4274)
				)
			)
		)
	)
	(footprint ""
		(layer "B.Cu")
		(at 346.821506 -2.152904 -90)
		(property "Reference" "C7G42"
			(at 0 0 90)
			(layer "B.SilkS")
			(hide yes)
			(effects
				(font
					(size 1.27 1.27)
				)
				(justify mirror)
			)
		)
		(property "Value" "*"
			(at -1.1811 -2.8194 270)
			(unlocked yes)
			(layer "B.Fab")
			(hide yes)
			(effects
				(font
					(size 1.27 1.016)
					(thickness 0.1524)
				)
				(justify mirror)
			)
		)
		(property "Device Type" "SC1U10V2KX-4-GP_SMD-BCG6-SC1U1A"
			(at -1.1811 -4.3434 270)
			(unlocked yes)
			(layer "B.Fab")
			(hide yes)
			(effects
				(font
					(size 1.27 1.016)
					(thickness 0.1524)
				)
				(justify mirror)
			)
		)
		(duplicate_pad_numbers_are_jumpers no)
		(fp_rect
			(start 0.4318 0.9525)
			(end -0.4318 -0.9525)
			(stroke
				(width 0)
				(type default)
			)
			(fill no)
			(layer "B.CrtYd")
		)
		(fp_rect
			(start 0.4318 0.9525)
			(end -0.4318 -0.9525)
			(stroke
				(width 0)
				(type default)
			)
			(fill no)
			(layer "B.Fab")
		)
		(pad "1" smd custom
			(at 0 -0.4445 90)
			(size 0.1524 0.1524)
			(layers "B.Cu" "B.Mask" "B.Paste")
			(net "P5V_STBY")
			(options
				(clearance outline)
				(anchor circle)
			)
			(primitives
				(gr_poly
					(pts
						(arc
							(start 0.3048 0.2032)
							(mid 0.275042 0.275042)
							(end 0.2032 0.3048)
						)
						(arc
							(start -0.2032 0.3048)
							(mid -0.275042 0.275042)
							(end -0.3048 0.2032)
						)
						(arc
							(start -0.3048 -0.2032)
							(mid -0.275042 -0.275042)
							(end -0.2032 -0.3048)
						)
						(arc
							(start 0.2032 -0.3048)
							(mid 0.275042 -0.275042)
							(end 0.3048 -0.2032)
						)
					)
					(width 0)
					(fill yes)
				)
			)
		)
		(pad "2" smd custom
			(at 0 0.4445 90)
			(size 0.1524 0.1524)
			(layers "B.Cu" "B.Mask" "B.Paste")
			(net "GND")
			(options
				(clearance outline)
				(anchor circle)
			)
			(primitives
				(gr_poly
					(pts
						(arc
							(start 0.3048 0.2032)
							(mid 0.275042 0.275042)
							(end 0.2032 0.3048)
						)
						(arc
							(start -0.2032 0.3048)
							(mid -0.275042 0.275042)
							(end -0.3048 0.2032)
						)
						(arc
							(start -0.3048 -0.2032)
							(mid -0.275042 -0.275042)
							(end -0.2032 -0.3048)
						)
						(arc
							(start 0.2032 -0.3048)
							(mid 0.275042 -0.275042)
							(end 0.3048 -0.2032)
						)
					)
					(width 0)
					(fill yes)
				)
			)
		)
	)
	(footprint ""
		(layer "B.Cu")
		(at 183.3626 -136.4234 180)
		(property "Reference" "C6L10"
			(at 0 0 0)
			(layer "B.SilkS")
			(hide yes)
			(effects
				(font
					(size 1.27 1.27)
				)
				(justify mirror)
			)
		)
		(property "Value" ""
			(at 0 0 0)
			(layer "B.Fab")
			(effects
				(font
					(size 1.27 1.27)
				)
				(justify mirror)
			)
		)
		(duplicate_pad_numbers_are_jumpers no)
		(fp_poly
			(pts
				(xy 0.7239 -0.2159) (xy -0.7239 -0.2159) (xy -0.7239 1.9939) (xy 0.7239 1.9939)
			)
			(stroke
				(width 0)
				(type default)
			)
			(fill no)
			(layer "B.CrtYd")
		)
		(fp_line
			(start 0.7239 1.9939)
			(end -0.7239 1.9939)
			(stroke
				(width 0.1)
				(type default)
			)
			(layer "B.Fab")
		)
		(fp_line
			(start 0.7239 -0.2159)
			(end 0.7239 1.9939)
			(stroke
				(width 0.1)
				(type default)
			)
			(layer "B.Fab")
		)
		(fp_line
			(start -0.7239 1.9939)
			(end -0.7239 -0.2159)
			(stroke
				(width 0.1)
				(type default)
			)
			(layer "B.Fab")
		)
		(fp_line
			(start -0.7239 -0.2159)
			(end 0.7239 -0.2159)
			(stroke
				(width 0.1)
				(type default)
			)
			(layer "B.Fab")
		)
		(pad "1" smd rect
			(at 0 0)
			(size 1.27 1.016)
			(layers "B.Cu" "B.Mask" "B.Paste")
			(net "VR_FET_SW_P12V_STBY_PVPP_KLM")
		)
		(pad "2" smd rect
			(at 0 1.778)
			(size 1.27 1.016)
			(layers "B.Cu" "B.Mask" "B.Paste")
			(net "GND")
		)
		(zone
			(layer "B.Cu")
			(hatch none 0.5)
			(connect_pads
				(clearance 0)
			)
			(min_thickness 0.25)
			(keepout
				(tracks not_allowed)
				(vias allowed)
				(pads allowed)
				(copperpour not_allowed)
				(footprints allowed)
			)
			(placement
				(enabled no)
				(sheetname "")
			)
			(fill
				(thermal_gap 0.5)
				(thermal_bridge_width 0.5)
				(island_removal_mode 0)
			)
			(polygon
				(pts
					(xy 182.7276 -136.9314) (xy 183.9976 -136.9314) (xy 183.9976 -137.6934) (xy 182.7276 -137.6934)
				)
			)
		)
	)
)
